(kicad_pcb
	(version 20260206)
	(generator "pcbnew")
	(generator_version "10.0")
	(general
		(thickness 1.6)
		(legacy_teardrops no)
	)
	(paper "A4")
	(title_block
		(title "04192023_DAF0TMB3IC0_F0TG_MB_C_brd_V02_OCP.brd")
		(comment 1 "Grand Teton / footprints 2696-2699 of 8354")
	)
	(layers
		(0 "F.Cu" signal "TOP")
		(4 "In1.Cu" signal "GND")
		(6 "In2.Cu" signal "IN1")
		(8 "In3.Cu" signal "GND1")
		(10 "In4.Cu" signal "IN2")
		(12 "In5.Cu" signal "GND2")
		(14 "In6.Cu" signal "IN3")
		(16 "In7.Cu" signal "GND3")
		(18 "In8.Cu" signal "VCC")
		(20 "In9.Cu" signal "VCC1")
		(22 "In10.Cu" signal "GND4")
		(24 "In11.Cu" signal "IN4")
		(26 "In12.Cu" signal "GND5")
		(28 "In13.Cu" signal "IN5")
		(30 "In14.Cu" signal "GND6")
		(32 "In15.Cu" signal "IN6")
		(34 "In16.Cu" signal "GND7")
		(2 "B.Cu" signal "BOTTOM")
		(9 "F.Adhes" user "F.Adhesive")
		(11 "B.Adhes" user "B.Adhesive")
		(13 "F.Paste" user "Package Geometry/Pastemask Top")
		(15 "B.Paste" user "Package Geometry/Pastemask Bottom")
		(5 "F.SilkS" user "Ref Des/Silkscreen Top")
		(7 "B.SilkS" user "Ref Des/Silkscreen Bottom")
		(1 "F.Mask" user "Board Geometry/Soldermask Top")
		(3 "B.Mask" user "Board Geometry/Soldermask Bottom")
		(17 "Dwgs.User" user "User.Drawings")
		(19 "Cmts.User" user "User.Comments")
		(21 "Eco1.User" user "User.Eco1")
		(23 "Eco2.User" user "User.Eco2")
		(25 "Edge.Cuts" user "Board Geometry/Outline")
		(27 "Margin" user)
		(31 "F.CrtYd" user "Package Geometry/Place Bound Top")
		(29 "B.CrtYd" user "Package Geometry/Place Bound Bottom")
		(35 "F.Fab" user "Ref Des/Assembly Top")
		(33 "B.Fab" user "Ref Des/Assembly Bottom")
	)
	(footprint ""
		(layer "F.Cu")
		(at 209.172556 -34.772092 90)
		(property "Reference" "U265"
			(at 3.273806 -3.826256 0)
			(unlocked yes)
			(layer "F.SilkS")
			(effects
				(font
					(size 0.7874 0.5842)
					(thickness 0.1524)
				)
			)
		)
		(property "Value" ""
			(at 0 0 90)
			(layer "F.Fab")
			(effects
				(font
					(size 1.27 1.27)
				)
			)
		)
		(duplicate_pad_numbers_are_jumpers no)
		(fp_line
			(start 1.500124 -1.500124)
			(end 1.500124 -1.004062)
			(stroke
				(width 0.1524)
				(type default)
			)
			(layer "F.SilkS")
		)
		(fp_line
			(start 1.004062 -1.500124)
			(end 1.500124 -1.500124)
			(stroke
				(width 0.1524)
				(type default)
			)
			(layer "F.SilkS")
		)
		(fp_line
			(start -1.500124 -1.500124)
			(end -1.004062 -1.500124)
			(stroke
				(width 0.1524)
				(type default)
			)
			(layer "F.SilkS")
		)
		(fp_line
			(start -1.500124 -1.004062)
			(end -1.500124 -1.500124)
			(stroke
				(width 0.1524)
				(type default)
			)
			(layer "F.SilkS")
		)
		(fp_line
			(start 1.500124 1.004062)
			(end 1.500124 1.500124)
			(stroke
				(width 0.1524)
				(type default)
			)
			(layer "F.SilkS")
		)
		(fp_line
			(start 1.500124 1.500124)
			(end 1.004062 1.500124)
			(stroke
				(width 0.1524)
				(type default)
			)
			(layer "F.SilkS")
		)
		(fp_line
			(start -1.004062 1.500124)
			(end -1.500124 1.500124)
			(stroke
				(width 0.1524)
				(type default)
			)
			(layer "F.SilkS")
		)
		(fp_line
			(start -1.500124 1.500124)
			(end -1.500124 1.004062)
			(stroke
				(width 0.1524)
				(type default)
			)
			(layer "F.SilkS")
		)
		(fp_poly
			(pts
				(xy -2.868422 -1.547368) (xy -2.15011 -2.265934) (xy -1.790954 -1.188212)
			)
			(stroke
				(width 0)
				(type default)
			)
			(fill yes)
			(layer "F.SilkS")
		)
		(fp_line
			(start 1.500124 -1.500124)
			(end 1.500124 1.500124)
			(stroke
				(width 0.1)
				(type default)
			)
			(layer "F.Fab")
		)
		(fp_line
			(start -1.500124 -1.500124)
			(end 1.500124 -1.500124)
			(stroke
				(width 0.1)
				(type default)
			)
			(layer "F.Fab")
		)
		(fp_line
			(start 1.500124 1.500124)
			(end -1.500124 1.500124)
			(stroke
				(width 0.1)
				(type default)
			)
			(layer "F.Fab")
		)
		(fp_line
			(start -1.500124 1.500124)
			(end -1.500124 -1.500124)
			(stroke
				(width 0.1)
				(type default)
			)
			(layer "F.Fab")
		)
		(fp_poly
			(pts
				(xy -2.847848 -1.258062) (xy -2.847848 -0.242062) (xy -1.831848 -0.750062)
			)
			(stroke
				(width 0)
				(type default)
			)
			(fill yes)
			(layer "F.Fab")
		)
		(pad "1" smd rect
			(at -1.400048 -0.750062)
			(size 0.2286 0.6096)
			(layers "F.Cu" "F.Mask" "F.Paste")
			(net "INA230_5_A1")
		)
		(pad "2" smd rect
			(at -1.400048 -0.249936)
			(size 0.2286 0.6096)
			(layers "F.Cu" "F.Mask" "F.Paste")
			(net "INA230_5_A0")
		)
		(pad "3" smd rect
			(at -1.400048 0.249936)
			(size 0.2286 0.6096)
			(layers "F.Cu" "F.Mask" "F.Paste")
			(net "P12V_SCM_ADC_ALERT_R")
		)
		(pad "4" smd rect
			(at -1.400048 0.750062)
			(size 0.2286 0.6096)
			(layers "F.Cu" "F.Mask" "F.Paste")
			(net "SMB_INA230_5_3V3AUX_SDA_R1")
		)
		(pad "5" smd rect
			(at -0.750062 1.400048 90)
			(size 0.2286 0.6096)
			(layers "F.Cu" "F.Mask" "F.Paste")
			(net "SMB_INA230_5_3V3AUX_SCL_R1")
		)
		(pad "6" smd rect
			(at -0.249936 1.400048 90)
			(size 0.2286 0.6096)
			(layers "F.Cu" "F.Mask" "F.Paste")
			(net "NC_INA230_5_NC0")
		)
		(pad "7" smd rect
			(at 0.249936 1.400048 90)
			(size 0.2286 0.6096)
			(layers "F.Cu" "F.Mask" "F.Paste")
			(net "NC_INA230_5_NC1")
		)
		(pad "8" smd rect
			(at 0.750062 1.400048 90)
			(size 0.2286 0.6096)
			(layers "F.Cu" "F.Mask" "F.Paste")
			(net "NC_INA230_5_NC2")
		)
		(pad "9" smd rect
			(at 1.400048 0.750062)
			(size 0.2286 0.6096)
			(layers "F.Cu" "F.Mask" "F.Paste")
			(net "P3V3_AUX")
		)
		(pad "10" smd rect
			(at 1.400048 0.249936)
			(size 0.2286 0.6096)
			(layers "F.Cu" "F.Mask" "F.Paste")
			(net "GND")
		)
		(pad "11" smd rect
			(at 1.400048 -0.249936)
			(size 0.2286 0.6096)
			(layers "F.Cu" "F.Mask" "F.Paste")
			(net "P12V_SCM_R")
		)
		(pad "12" smd rect
			(at 1.400048 -0.750062)
			(size 0.2286 0.6096)
			(layers "F.Cu" "F.Mask" "F.Paste")
			(net "VSENSE_P12V_INA230_5_INN")
		)
		(pad "13" smd rect
			(at 0.750062 -1.400048 90)
			(size 0.2286 0.6096)
			(layers "F.Cu" "F.Mask" "F.Paste")
			(net "VSENSE_P12V_INA230_5_INP")
		)
		(pad "14" smd rect
			(at 0.249936 -1.400048 90)
			(size 0.2286 0.6096)
			(layers "F.Cu" "F.Mask" "F.Paste")
			(net "NC_INA230_5_NC3")
		)
		(pad "15" smd rect
			(at -0.249936 -1.400048 90)
			(size 0.2286 0.6096)
			(layers "F.Cu" "F.Mask" "F.Paste")
			(net "NC_INA230_5_NC4")
		)
		(pad "16" smd rect
			(at -0.750062 -1.400048 90)
			(size 0.2286 0.6096)
			(layers "F.Cu" "F.Mask" "F.Paste")
			(net "NC_INA230_5_NC5")
		)
		(pad "TH" smd rect
			(at 0 0 90)
			(size 1.7018 1.7018)
			(layers "F.Cu" "F.Mask" "F.Paste")
			(net "GND")
		)
		(zone
			(layer "F.Cu")
			(hatch none 0.5)
			(connect_pads
				(clearance 0)
			)
			(min_thickness 0.25)
			(keepout
				(tracks not_allowed)
				(vias allowed)
				(pads allowed)
				(copperpour not_allowed)
				(footprints allowed)
			)
			(placement
				(enabled no)
				(sheetname "")
			)
			(fill
				(thermal_gap 0.5)
				(thermal_bridge_width 0.5)
				(island_removal_mode 0)
			)
			(polygon
				(pts
					(xy 209.147156 -33.727644) (xy 208.128108 -33.727644) (xy 208.128108 -35.81654) (xy 210.217004 -35.81654)
					(xy 210.217004 -33.727644) (xy 209.172556 -33.727644) (xy 209.172556 -33.870392) (xy 210.074256 -33.870392)
					(xy 210.074256 -35.673792) (xy 208.270856 -35.673792) (xy 208.270856 -33.870392) (xy 209.147156 -33.870392)
				)
			)
		)
	)
	(footprint ""
		(layer "F.Cu")
		(at 346.549726 -28.291028 -90)
		(property "Reference" "U86"
			(at 1.804416 -2.63652 90)
			(unlocked yes)
			(layer "F.SilkS")
			(effects
				(font
					(size 0.7874 0.5842)
					(thickness 0.1524)
				)
				(justify left)
			)
		)
		(property "Value" ""
			(at 0 0 270)
			(layer "F.Fab")
			(effects
				(font
					(size 1.27 1.27)
				)
			)
		)
		(duplicate_pad_numbers_are_jumpers no)
		(fp_line
			(start -2.0574 1.651)
			(end -2.0574 -1.651)
			(stroke
				(width 0.1524)
				(type default)
			)
			(layer "F.SilkS")
		)
		(fp_line
			(start 2.0574 1.651)
			(end -2.0574 1.651)
			(stroke
				(width 0.1524)
				(type default)
			)
			(layer "F.SilkS")
		)
		(fp_line
			(start 0 -1.016)
			(end 0.381 -1.651)
			(stroke
				(width 0.1524)
				(type default)
			)
			(layer "F.SilkS")
		)
		(fp_line
			(start -2.0574 -1.651)
			(end -0.381 -1.651)
			(stroke
				(width 0.1524)
				(type default)
			)
			(layer "F.SilkS")
		)
		(fp_line
			(start -0.381 -1.651)
			(end 0 -1.016)
			(stroke
				(width 0.1524)
				(type default)
			)
			(layer "F.SilkS")
		)
		(fp_line
			(start 0.381 -1.651)
			(end 2.0574 -1.651)
			(stroke
				(width 0.1524)
				(type default)
			)
			(layer "F.SilkS")
		)
		(fp_line
			(start 2.0574 -1.651)
			(end 2.0574 1.651)
			(stroke
				(width 0.1524)
				(type default)
			)
			(layer "F.SilkS")
		)
		(fp_poly
			(pts
				(xy -2.159 -1.016) (xy -2.71272 -0.719328) (xy -2.71272 -1.344168)
			)
			(stroke
				(width 0)
				(type default)
			)
			(fill yes)
			(layer "F.SilkS")
		)
		(fp_line
			(start -0.899922 1.549908)
			(end -0.899922 1.199896)
			(stroke
				(width 0.1)
				(type default)
			)
			(layer "F.Fab")
		)
		(fp_line
			(start 0.899922 1.549908)
			(end -0.899922 1.549908)
			(stroke
				(width 0.1)
				(type default)
			)
			(layer "F.Fab")
		)
		(fp_line
			(start -1.599946 1.199896)
			(end -1.599946 -1.199896)
			(stroke
				(width 0.1)
				(type default)
			)
			(layer "F.Fab")
		)
		(fp_line
			(start -0.899922 1.199896)
			(end -1.599946 1.199896)
			(stroke
				(width 0.1)
				(type default)
			)
			(layer "F.Fab")
		)
		(fp_line
			(start 0.899922 1.199896)
			(end 0.899922 1.549908)
			(stroke
				(width 0.1)
				(type default)
			)
			(layer "F.Fab")
		)
		(fp_line
			(start 1.599946 1.199896)
			(end 0.899922 1.199896)
			(stroke
				(width 0.1)
				(type default)
			)
			(layer "F.Fab")
		)
		(fp_line
			(start -1.599946 -1.199896)
			(end -0.899922 -1.199896)
			(stroke
				(width 0.1)
				(type default)
			)
			(layer "F.Fab")
		)
		(fp_line
			(start -0.899922 -1.199896)
			(end -0.899922 -1.549908)
			(stroke
				(width 0.1)
				(type default)
			)
			(layer "F.Fab")
		)
		(fp_line
			(start 0.899922 -1.199896)
			(end 1.599946 -1.199896)
			(stroke
				(width 0.1)
				(type default)
			)
			(layer "F.Fab")
		)
		(fp_line
			(start 1.599946 -1.199896)
			(end 1.599946 1.199896)
			(stroke
				(width 0.1)
				(type default)
			)
			(layer "F.Fab")
		)
		(fp_line
			(start -0.899922 -1.549908)
			(end 0.899922 -1.549908)
			(stroke
				(width 0.1)
				(type default)
			)
			(layer "F.Fab")
		)
		(fp_line
			(start 0.899922 -1.549908)
			(end 0.899922 -1.199896)
			(stroke
				(width 0.1)
				(type default)
			)
			(layer "F.Fab")
		)
		(fp_poly
			(pts
				(xy -2.71272 -0.719328) (xy -2.71272 -1.344168) (xy -2.159 -1.016)
			)
			(stroke
				(width 0)
				(type default)
			)
			(fill yes)
			(layer "F.Fab")
		)
		(pad "1" smd rect
			(at -1.225042 -0.94996 180)
			(size 0.5588 1.3462)
			(layers "F.Cu" "F.Mask" "F.Paste")
			(net "Net_10731")
		)
		(pad "2" smd rect
			(at -1.225042 0 180)
			(size 0.5588 1.3462)
			(layers "F.Cu" "F.Mask" "F.Paste")
			(net "FM_SMERR_LED_N")
		)
		(pad "3" smd rect
			(at -1.225042 0.94996 180)
			(size 0.5588 1.3462)
			(layers "F.Cu" "F.Mask" "F.Paste")
			(net "GND")
		)
		(pad "4" smd rect
			(at 1.225042 0.94996 180)
			(size 0.5588 1.3462)
			(layers "F.Cu" "F.Mask" "F.Paste")
			(net "FM_SMERR_BUF_LED_N")
		)
		(pad "5" smd rect
			(at 1.225042 -0.94996 180)
			(size 0.5588 1.3462)
			(layers "F.Cu" "F.Mask" "F.Paste")
			(net "P1V8_AUX")
		)
	)
	(footprint ""
		(layer "F.Cu")
		(at 55.329328 -351.372932 -90)
		(property "Reference" "PC447"
			(at 0 0 270)
			(layer "F.SilkS")
			(hide yes)
			(effects
				(font
					(size 1.27 1.27)
				)
			)
		)
		(property "Value" ""
			(at 0 0 270)
			(layer "F.Fab")
			(effects
				(font
					(size 1.27 1.27)
				)
			)
		)
		(duplicate_pad_numbers_are_jumpers no)
		(fp_line
			(start -0.7874 0.4064)
			(end -0.7874 -0.4064)
			(stroke
				(width 0.1524)
				(type default)
			)
			(layer "F.SilkS")
		)
		(fp_line
			(start 0.7874 0.4064)
			(end -0.7874 0.4064)
			(stroke
				(width 0.1524)
				(type default)
			)
			(layer "F.SilkS")
		)
		(fp_line
			(start -0.7874 -0.4064)
			(end 0.7874 -0.4064)
			(stroke
				(width 0.1524)
				(type default)
			)
			(layer "F.SilkS")
		)
		(fp_line
			(start 0.7874 -0.4064)
			(end 0.7874 0.4064)
			(stroke
				(width 0.1524)
				(type default)
			)
			(layer "F.SilkS")
		)
		(fp_line
			(start -0.67945 0.3048)
			(end -0.67945 -0.305054)
			(stroke
				(width 0.1)
				(type default)
			)
			(layer "F.Fab")
		)
		(fp_line
			(start -0.12065 0.3048)
			(end -0.67945 0.3048)
			(stroke
				(width 0.1)
				(type default)
			)
			(layer "F.Fab")
		)
		(fp_line
			(start 0.120396 0.3048)
			(end 0.120396 0.2794)
			(stroke
				(width 0.1)
				(type default)
			)
			(layer "F.Fab")
		)
		(fp_line
			(start 0.67945 0.3048)
			(end 0.120396 0.3048)
			(stroke
				(width 0.1)
				(type default)
			)
			(layer "F.Fab")
		)
		(fp_line
			(start -0.12065 0.2794)
			(end -0.12065 0.3048)
			(stroke
				(width 0.1)
				(type default)
			)
			(layer "F.Fab")
		)
		(fp_line
			(start 0.120396 0.2794)
			(end -0.12065 0.2794)
			(stroke
				(width 0.1)
				(type default)
			)
			(layer "F.Fab")
		)
		(fp_line
			(start -0.12065 -0.2794)
			(end 0.12065 -0.2794)
			(stroke
				(width 0.1)
				(type default)
			)
			(layer "F.Fab")
		)
		(fp_line
			(start 0.12065 -0.2794)
			(end 0.12065 -0.3048)
			(stroke
				(width 0.1)
				(type default)
			)
			(layer "F.Fab")
		)
		(fp_line
			(start 0.12065 -0.3048)
			(end 0.67945 -0.3048)
			(stroke
				(width 0.1)
				(type default)
			)
			(layer "F.Fab")
		)
		(fp_line
			(start 0.67945 -0.3048)
			(end 0.67945 0.3048)
			(stroke
				(width 0.1)
				(type default)
			)
			(layer "F.Fab")
		)
		(fp_line
			(start -0.67945 -0.305054)
			(end -0.12065 -0.305054)
			(stroke
				(width 0.1)
				(type default)
			)
			(layer "F.Fab")
		)
		(fp_line
			(start -0.12065 -0.305054)
			(end -0.12065 -0.2794)
			(stroke
				(width 0.1)
				(type default)
			)
			(layer "F.Fab")
		)
		(pad "1" smd circle
			(at -0.40005 0 270)
			(size 0 0)
			(layers "F.Cu" "F.Mask" "F.Paste")
			(net "SW_PVDDIO_P1_BOOT1_R")
		)
		(pad "2" smd circle
			(at 0.40005 0 270)
			(size 0 0)
			(layers "F.Cu" "F.Mask" "F.Paste")
			(net "SW_PVDDIO_P1_BOOTR1")
		)
	)
	(footprint ""
		(layer "F.Cu")
		(at 115.815872 -73.954132 90)
		(property "Reference" "PL6003"
			(at 0 0 90)
			(layer "F.SilkS")
			(hide yes)
			(effects
				(font
					(size 1.27 1.27)
				)
			)
		)
		(property "Value" ""
			(at 0 0 90)
			(layer "F.Fab")
			(effects
				(font
					(size 1.27 1.27)
				)
			)
		)
		(duplicate_pad_numbers_are_jumpers no)
		(fp_line
			(start -1.27 -0.5842)
			(end 1.27 -0.5842)
			(stroke
				(width 0.1524)
				(type default)
			)
			(layer "F.SilkS")
		)
		(fp_line
			(start -1.27 -0.5588)
			(end -1.27 -0.5842)
			(stroke
				(width 0.1524)
				(type default)
			)
			(layer "F.SilkS")
		)
		(fp_line
			(start 1.27 0.5842)
			(end 1.27 -0.5842)
			(stroke
				(width 0.1524)
				(type default)
			)
			(layer "F.SilkS")
		)
		(fp_line
			(start 1.27 0.5842)
			(end -1.27 0.5842)
			(stroke
				(width 0.1524)
				(type default)
			)
			(layer "F.SilkS")
		)
		(fp_line
			(start -1.27 0.5842)
			(end -1.27 -0.5842)
			(stroke
				(width 0.1524)
				(type default)
			)
			(layer "F.SilkS")
		)
		(fp_line
			(start 0.9144 -0.508)
			(end 0.9144 -0.406654)
			(stroke
				(width 0.1)
				(type default)
			)
			(layer "F.Fab")
		)
		(fp_line
			(start -0.9144 -0.508)
			(end 0.9144 -0.508)
			(stroke
				(width 0.1)
				(type default)
			)
			(layer "F.Fab")
		)
		(fp_line
			(start 1.1938 -0.406654)
			(end 1.1938 0.4064)
			(stroke
				(width 0.1)
				(type default)
			)
			(layer "F.Fab")
		)
		(fp_line
			(start 0.9144 -0.406654)
			(end 1.1938 -0.406654)
			(stroke
				(width 0.1)
				(type default)
			)
			(layer "F.Fab")
		)
		(fp_line
			(start -0.9144 -0.406654)
			(end -0.9144 -0.508)
			(stroke
				(width 0.1)
				(type default)
			)
			(layer "F.Fab")
		)
		(fp_line
			(start -1.194308 -0.406654)
			(end -0.9144 -0.406654)
			(stroke
				(width 0.1)
				(type default)
			)
			(layer "F.Fab")
		)
		(fp_line
			(start 1.1938 0.4064)
			(end 0.9144 0.4064)
			(stroke
				(width 0.1)
				(type default)
			)
			(layer "F.Fab")
		)
		(fp_line
			(start 0.9144 0.4064)
			(end 0.9144 0.508)
			(stroke
				(width 0.1)
				(type default)
			)
			(layer "F.Fab")
		)
		(fp_line
			(start -0.9144 0.406654)
			(end -1.194308 0.406654)
			(stroke
				(width 0.1)
				(type default)
			)
			(layer "F.Fab")
		)
		(fp_line
			(start -1.194308 0.406654)
			(end -1.194308 -0.406654)
			(stroke
				(width 0.1)
				(type default)
			)
			(layer "F.Fab")
		)
		(fp_line
			(start 0.9144 0.508)
			(end -0.9144 0.508)
			(stroke
				(width 0.1)
				(type default)
			)
			(layer "F.Fab")
		)
		(fp_line
			(start -0.9144 0.508)
			(end -0.9144 0.406654)
			(stroke
				(width 0.1)
				(type default)
			)
			(layer "F.Fab")
		)
		(pad "1" smd rect
			(at -0.7366 0)
			(size 0.7112 0.8128)
			(layers "F.Cu" "F.Mask" "F.Paste")
			(net "P12V_AUX")
		)
		(pad "2" smd rect
			(at 0.7366 0)
			(size 0.7112 0.8128)
			(layers "F.Cu" "F.Mask" "F.Paste")
			(net "SW_P12V_AUX_P1V2_AUX_FLT")
		)
	)
)
